# T6G (Grand Teton) — schematic netlist excerpt (pin names and nets, part order shuffled) for the footprints in the layout excerpt that follows; sources: Cadence DE-HDL packaged netlist, KiCad conversion of 04192023_DAF0TMB3IC0_F0TG_MB_C_brd_V02_OCP.brd

PR327  Q_RES  2.2 1% CHIP  pkg 0402LF  page 225 : A = PVDD11_S3_P1_PVCC ; B = PVDD11_S3_P1_VCC2
PR150  Q_RES  0 5% CHIP  pkg 0402LF  page 210 : A = SVID_PVDDCR_CPU0_P1_SVTI ; B = GND

(kicad_pcb
	(version 20260206)
	(generator "pcbnew")
	(generator_version "10.0")
	(general
		(thickness 1.6)
		(legacy_teardrops no)
	)
	(paper "A4")
	(title_block
		(title "04192023_DAF0TMB3IC0_F0TG_MB_C_brd_V02_OCP.brd")
		(comment 1 "Grand Teton / footprints 7500-7501 of 8354")
	)
	(layers
		(0 "F.Cu" signal "TOP")
		(4 "In1.Cu" signal "GND")
		(6 "In2.Cu" signal "IN1")
		(8 "In3.Cu" signal "GND1")
		(10 "In4.Cu" signal "IN2")
		(12 "In5.Cu" signal "GND2")
		(14 "In6.Cu" signal "IN3")
		(16 "In7.Cu" signal "GND3")
		(18 "In8.Cu" signal "VCC")
		(20 "In9.Cu" signal "VCC1")
		(22 "In10.Cu" signal "GND4")
		(24 "In11.Cu" signal "IN4")
		(26 "In12.Cu" signal "GND5")
		(28 "In13.Cu" signal "IN5")
		(30 "In14.Cu" signal "GND6")
		(32 "In15.Cu" signal "IN6")
		(34 "In16.Cu" signal "GND7")
		(2 "B.Cu" signal "BOTTOM")
		(9 "F.Adhes" user "F.Adhesive")
		(11 "B.Adhes" user "B.Adhesive")
		(13 "F.Paste" user "Package Geometry/Pastemask Top")
		(15 "B.Paste" user "Package Geometry/Pastemask Bottom")
		(5 "F.SilkS" user "Ref Des/Silkscreen Top")
		(7 "B.SilkS" user "Ref Des/Silkscreen Bottom")
		(1 "F.Mask" user "Board Geometry/Soldermask Top")
		(3 "B.Mask" user "Board Geometry/Soldermask Bottom")
		(17 "Dwgs.User" user "User.Drawings")
		(19 "Cmts.User" user "User.Comments")
		(21 "Eco1.User" user "User.Eco1")
		(23 "Eco2.User" user "User.Eco2")
		(25 "Edge.Cuts" user "Board Geometry/Outline")
		(27 "Margin" user)
		(31 "F.CrtYd" user "Package Geometry/Place Bound Top")
		(29 "B.CrtYd" user "Package Geometry/Place Bound Bottom")
		(35 "F.Fab" user "Ref Des/Assembly Top")
		(33 "B.Fab" user "Ref Des/Assembly Bottom")
	)
	(footprint ""
		(layer "B.Cu")
		(at 188.935614 -352.380042 -90)
		(property "Reference" "PR327"
			(at 0 0 90)
			(layer "B.SilkS")
			(hide yes)
			(effects
				(font
					(size 1.27 1.27)
				)
				(justify mirror)
			)
		)
		(property "Value" ""
			(at 0 0 90)
			(layer "B.Fab")
			(effects
				(font
					(size 1.27 1.27)
				)
				(justify mirror)
			)
		)
		(duplicate_pad_numbers_are_jumpers no)
		(fp_line
			(start -0.7874 0.4064)
			(end 0.7874 0.4064)
			(stroke
				(width 0.1524)
				(type default)
			)
			(layer "B.SilkS")
		)
		(fp_line
			(start 0.7874 0.4064)
			(end 0.7874 -0.4064)
			(stroke
				(width 0.1524)
				(type default)
			)
			(layer "B.SilkS")
		)
		(fp_line
			(start -0.7874 -0.4064)
			(end -0.7874 0.4064)
			(stroke
				(width 0.1524)
				(type default)
			)
			(layer "B.SilkS")
		)
		(fp_line
			(start 0.7874 -0.4064)
			(end -0.7874 -0.4064)
			(stroke
				(width 0.1524)
				(type default)
			)
			(layer "B.SilkS")
		)
		(fp_line
			(start -0.67945 0.3048)
			(end -0.120396 0.3048)
			(stroke
				(width 0.1)
				(type default)
			)
			(layer "B.Fab")
		)
		(fp_line
			(start -0.120396 0.3048)
			(end -0.120396 0.2794)
			(stroke
				(width 0.1)
				(type default)
			)
			(layer "B.Fab")
		)
		(fp_line
			(start 0.12065 0.3048)
			(end 0.67945 0.3048)
			(stroke
				(width 0.1)
				(type default)
			)
			(layer "B.Fab")
		)
		(fp_line
			(start 0.67945 0.3048)
			(end 0.67945 -0.305054)
			(stroke
				(width 0.1)
				(type default)
			)
			(layer "B.Fab")
		)
		(fp_line
			(start -0.120396 0.2794)
			(end 0.12065 0.2794)
			(stroke
				(width 0.1)
				(type default)
			)
			(layer "B.Fab")
		)
		(fp_line
			(start 0.12065 0.2794)
			(end 0.12065 0.3048)
			(stroke
				(width 0.1)
				(type default)
			)
			(layer "B.Fab")
		)
		(fp_line
			(start -0.12065 -0.2794)
			(end -0.12065 -0.3048)
			(stroke
				(width 0.1)
				(type default)
			)
			(layer "B.Fab")
		)
		(fp_line
			(start 0.12065 -0.2794)
			(end -0.12065 -0.2794)
			(stroke
				(width 0.1)
				(type default)
			)
			(layer "B.Fab")
		)
		(fp_line
			(start -0.67945 -0.3048)
			(end -0.67945 0.3048)
			(stroke
				(width 0.1)
				(type default)
			)
			(layer "B.Fab")
		)
		(fp_line
			(start -0.12065 -0.3048)
			(end -0.67945 -0.3048)
			(stroke
				(width 0.1)
				(type default)
			)
			(layer "B.Fab")
		)
		(fp_line
			(start 0.12065 -0.305054)
			(end 0.12065 -0.2794)
			(stroke
				(width 0.1)
				(type default)
			)
			(layer "B.Fab")
		)
		(fp_line
			(start 0.67945 -0.305054)
			(end 0.12065 -0.305054)
			(stroke
				(width 0.1)
				(type default)
			)
			(layer "B.Fab")
		)
		(pad "1" smd circle
			(at 0.40005 0 90)
			(size 0 0)
			(layers "B.Cu" "B.Mask" "B.Paste")
			(net "PVDD11_S3_P1_PVCC")
		)
		(pad "2" smd circle
			(at -0.40005 0 90)
			(size 0 0)
			(layers "B.Cu" "B.Mask" "B.Paste")
			(net "PVDD11_S3_P1_VCC2")
		)
	)
	(footprint ""
		(layer "B.Cu")
		(at 88.177878 -150.19909)
		(property "Reference" "PR150"
			(at 0 0 0)
			(layer "B.SilkS")
			(hide yes)
			(effects
				(font
					(size 1.27 1.27)
				)
				(justify mirror)
			)
		)
		(property "Value" ""
			(at 0 0 0)
			(layer "B.Fab")
			(effects
				(font
					(size 1.27 1.27)
				)
				(justify mirror)
			)
		)
		(duplicate_pad_numbers_are_jumpers no)
		(fp_line
			(start -0.7874 -0.4064)
			(end -0.7874 0.4064)
			(stroke
				(width 0.1524)
				(type default)
			)
			(layer "B.SilkS")
		)
		(fp_line
			(start -0.7874 0.4064)
			(end 0.7874 0.4064)
			(stroke
				(width 0.1524)
				(type default)
			)
			(layer "B.SilkS")
		)
		(fp_line
			(start 0.7874 -0.4064)
			(end -0.7874 -0.4064)
			(stroke
				(width 0.1524)
				(type default)
			)
			(layer "B.SilkS")
		)
		(fp_line
			(start 0.7874 0.4064)
			(end 0.7874 -0.4064)
			(stroke
				(width 0.1524)
				(type default)
			)
			(layer "B.SilkS")
		)
		(fp_line
			(start -0.67945 -0.3048)
			(end -0.67945 0.3048)
			(stroke
				(width 0.1)
				(type default)
			)
			(layer "B.Fab")
		)
		(fp_line
			(start -0.67945 0.3048)
			(end -0.120396 0.3048)
			(stroke
				(width 0.1)
				(type default)
			)
			(layer "B.Fab")
		)
		(fp_line
			(start -0.12065 -0.3048)
			(end -0.67945 -0.3048)
			(stroke
				(width 0.1)
				(type default)
			)
			(layer "B.Fab")
		)
		(fp_line
			(start -0.12065 -0.2794)
			(end -0.12065 -0.3048)
			(stroke
				(width 0.1)
				(type default)
			)
			(layer "B.Fab")
		)
		(fp_line
			(start -0.120396 0.2794)
			(end 0.12065 0.2794)
			(stroke
				(width 0.1)
				(type default)
			)
			(layer "B.Fab")
		)
		(fp_line
			(start -0.120396 0.3048)
			(end -0.120396 0.2794)
			(stroke
				(width 0.1)
				(type default)
			)
			(layer "B.Fab")
		)
		(fp_line
			(start 0.12065 -0.305054)
			(end 0.12065 -0.2794)
			(stroke
				(width 0.1)
				(type default)
			)
			(layer "B.Fab")
		)
		(fp_line
			(start 0.12065 -0.2794)
			(end -0.12065 -0.2794)
			(stroke
				(width 0.1)
				(type default)
			)
			(layer "B.Fab")
		)
		(fp_line
			(start 0.12065 0.2794)
			(end 0.12065 0.3048)
			(stroke
				(width 0.1)
				(type default)
			)
			(layer "B.Fab")
		)
		(fp_line
			(start 0.12065 0.3048)
			(end 0.67945 0.3048)
			(stroke
				(width 0.1)
				(type default)
			)
			(layer "B.Fab")
		)
		(fp_line
			(start 0.67945 -0.305054)
			(end 0.12065 -0.305054)
			(stroke
				(width 0.1)
				(type default)
			)
			(layer "B.Fab")
		)
		(fp_line
			(start 0.67945 0.3048)
			(end 0.67945 -0.305054)
			(stroke
				(width 0.1)
				(type default)
			)
			(layer "B.Fab")
		)
		(pad "1" smd circle
			(at 0.40005 0 180)
			(size 0 0)
			(layers "B.Cu" "B.Mask" "B.Paste")
			(net "SVID_PVDDCR_CPU0_P1_SVTI")
		)
		(pad "2" smd circle
			(at -0.40005 0 180)
			(size 0 0)
			(layers "B.Cu" "B.Mask" "B.Paste")
			(net "GND")
		)
	)
)
